(kicad_pcb
	(version 20260206)
	(generator "pcbnew")
	(generator_version "10.0")
	(general
		(thickness 1.6)
		(legacy_teardrops no)
	)
	(paper "A4")
	(title_block
		(title "Bryce Canyon_F.DPB_16315-1-OCP.brd")
		(comment 1 "Bryce Canyon / footprint 2079 of 2223 (IO1), pads 82-95 of 202")
	)
	(layers
		(0 "F.Cu" signal "TOP")
		(4 "In1.Cu" signal "L2GND")
		(6 "In2.Cu" signal "L3")
		(8 "In3.Cu" signal "L4GND")
		(10 "In4.Cu" signal "L5")
		(12 "In5.Cu" signal "L6VCC")
		(14 "In6.Cu" signal "L7VCC")
		(16 "In7.Cu" signal "L8")
		(18 "In8.Cu" signal "L9GND")
		(20 "In9.Cu" signal "L10")
		(22 "In10.Cu" signal "L11GND")
		(2 "B.Cu" signal "BOTTOM")
		(9 "F.Adhes" user "F.Adhesive")
		(11 "B.Adhes" user "B.Adhesive")
		(13 "F.Paste" user "Package Geometry/Pastemask Top")
		(15 "B.Paste" user "Package Geometry/Pastemask Bottom")
		(5 "F.SilkS" user "Ref Des/Silkscreen Top")
		(7 "B.SilkS" user "Ref Des/Silkscreen Bottom")
		(1 "F.Mask" user "Board Geometry/Soldermask Top")
		(3 "B.Mask" user "Board Geometry/Soldermask Bottom")
		(17 "Dwgs.User" user "User.Drawings")
		(19 "Cmts.User" user "User.Comments")
		(21 "Eco1.User" user "User.Eco1")
		(23 "Eco2.User" user "User.Eco2")
		(25 "Edge.Cuts" user "Board Geometry/Outline")
		(27 "Margin" user)
		(31 "F.CrtYd" user "Package Geometry/Place Bound Top")
		(29 "B.CrtYd" user "Package Geometry/Place Bound Bottom")
		(35 "F.Fab" user "Ref Des/Assembly Top")
		(33 "B.Fab" user "Ref Des/Assembly Bottom")
	)
	(footprint ""
		(layer "B.Cu")
		(at 143.34998 -30.550104 180)
		(property "Reference" "IO1"
			(at 0 0 0)
			(layer "B.SilkS")
			(hide yes)
			(effects
				(font
					(size 1.27 1.27)
				)
				(justify mirror)
			)
		)
		(property "Value" "DM-AMP-CONN200-13R-6-GP-01"
			(at 47.5488 -16.5862 180)
			(unlocked yes)
			(layer "B.Fab")
			(hide yes)
			(effects
				(font
					(size 1.016 1.016)
					(thickness 0.1524)
				)
				(justify mirror)
			)
		)
		(property "Device Type" "DMFIT-200P-384346H577-01"
			(at 47.5488 -18.1102 180)
			(unlocked yes)
			(layer "B.Fab")
			(hide yes)
			(effects
				(font
					(size 1.016 1.016)
					(thickness 0.1524)
				)
				(justify mirror)
			)
		)
		(duplicate_pad_numbers_are_jumpers no)
		(pad "E16" thru_hole circle
			(at 34.200084 -8.199882)
			(size 0.664718 0.664718)
			(drill 0.359918)
			(layers "*.Cu" "*.Mask")
			(remove_unused_layers no)
			(net "PCIE_IOM_A_TO_COMP_A_23_DN")
			(clearance 0.264414)
			(padstack
				(mode custom)
				(layer "In1.Cu"
					(shape circle)
					(size 0.664718 0.664718)
					(clearance 0.264414)
				)
				(layer "In2.Cu"
					(shape circle)
					(size 0.664718 0.664718)
					(clearance 0.264414)
				)
				(layer "In3.Cu"
					(shape circle)
					(size 0.664718 0.664718)
					(clearance 0.264414)
				)
				(layer "In4.Cu"
					(shape circle)
					(size 0.664718 0.664718)
					(clearance 0.264414)
				)
				(layer "In5.Cu"
					(shape circle)
					(size 0.664718 0.664718)
					(clearance 0.264414)
				)
				(layer "In6.Cu"
					(shape circle)
					(size 0.762 0.762)
					(clearance 0.1651)
				)
				(layer "In7.Cu"
					(shape circle)
					(size 0.762 0.762)
					(clearance 0.1651)
				)
				(layer "In8.Cu"
					(shape circle)
					(size 0.762 0.762)
					(clearance 0.1651)
				)
				(layer "In9.Cu"
					(shape circle)
					(size 0.762 0.762)
					(clearance 0.1651)
				)
				(layer "In10.Cu"
					(shape circle)
					(size 0.762 0.762)
					(clearance 0.1651)
				)
				(layer "B.Cu"
					(shape circle)
					(size 0.762 0.762)
					(thermal_gap 0.1651)
					(clearance 0.1651)
				)
			)
		)
		(pad "F1" thru_hole circle
			(at 0 -8.599932)
			(size 0.664718 0.664718)
			(drill 0.359918)
			(layers "*.Cu" "*.Mask")
			(remove_unused_layers no)
			(net "PCIE_IOM_A_TO_COMP_A_8_DP")
			(clearance 0.264414)
			(padstack
				(mode custom)
				(layer "In1.Cu"
					(shape circle)
					(size 0.664718 0.664718)
					(clearance 0.264414)
				)
				(layer "In2.Cu"
					(shape circle)
					(size 0.664718 0.664718)
					(clearance 0.264414)
				)
				(layer "In3.Cu"
					(shape circle)
					(size 0.664718 0.664718)
					(clearance 0.264414)
				)
				(layer "In4.Cu"
					(shape circle)
					(size 0.664718 0.664718)
					(clearance 0.264414)
				)
				(layer "In5.Cu"
					(shape circle)
					(size 0.664718 0.664718)
					(clearance 0.264414)
				)
				(layer "In6.Cu"
					(shape circle)
					(size 0.762 0.762)
					(clearance 0.1651)
				)
				(layer "In7.Cu"
					(shape circle)
					(size 0.762 0.762)
					(clearance 0.1651)
				)
				(layer "In8.Cu"
					(shape circle)
					(size 0.762 0.762)
					(clearance 0.1651)
				)
				(layer "In9.Cu"
					(shape circle)
					(size 0.762 0.762)
					(clearance 0.1651)
				)
				(layer "In10.Cu"
					(shape circle)
					(size 0.762 0.762)
					(clearance 0.1651)
				)
				(layer "B.Cu"
					(shape circle)
					(size 0.762 0.762)
					(thermal_gap 0.1651)
					(clearance 0.1651)
				)
			)
		)
		(pad "F2" thru_hole circle
			(at 1.800098 -9.59993)
			(size 0.664718 0.664718)
			(drill 0.359918)
			(layers "*.Cu" "*.Mask")
			(remove_unused_layers no)
			(net "PCIE_IOM_A_TO_COMP_A_9_DP")
			(clearance 0.264414)
			(padstack
				(mode custom)
				(layer "In1.Cu"
					(shape circle)
					(size 0.664718 0.664718)
					(clearance 0.264414)
				)
				(layer "In2.Cu"
					(shape circle)
					(size 0.664718 0.664718)
					(clearance 0.264414)
				)
				(layer "In3.Cu"
					(shape circle)
					(size 0.664718 0.664718)
					(clearance 0.264414)
				)
				(layer "In4.Cu"
					(shape circle)
					(size 0.664718 0.664718)
					(clearance 0.264414)
				)
				(layer "In5.Cu"
					(shape circle)
					(size 0.664718 0.664718)
					(clearance 0.264414)
				)
				(layer "In6.Cu"
					(shape circle)
					(size 0.762 0.762)
					(clearance 0.1651)
				)
				(layer "In7.Cu"
					(shape circle)
					(size 0.762 0.762)
					(clearance 0.1651)
				)
				(layer "In8.Cu"
					(shape circle)
					(size 0.762 0.762)
					(clearance 0.1651)
				)
				(layer "In9.Cu"
					(shape circle)
					(size 0.762 0.762)
					(clearance 0.1651)
				)
				(layer "In10.Cu"
					(shape circle)
					(size 0.762 0.762)
					(clearance 0.1651)
				)
				(layer "B.Cu"
					(shape circle)
					(size 0.762 0.762)
					(thermal_gap 0.1651)
					(clearance 0.1651)
				)
			)
		)
		(pad "F3" thru_hole circle
			(at 3.599942 -8.599932)
			(size 0.664718 0.664718)
			(drill 0.359918)
			(layers "*.Cu" "*.Mask")
			(remove_unused_layers no)
			(net "PCIE_IOM_A_TO_COMP_A_10_DP")
			(clearance 0.264414)
			(padstack
				(mode custom)
				(layer "In1.Cu"
					(shape circle)
					(size 0.664718 0.664718)
					(clearance 0.264414)
				)
				(layer "In2.Cu"
					(shape circle)
					(size 0.664718 0.664718)
					(clearance 0.264414)
				)
				(layer "In3.Cu"
					(shape circle)
					(size 0.664718 0.664718)
					(clearance 0.264414)
				)
				(layer "In4.Cu"
					(shape circle)
					(size 0.664718 0.664718)
					(clearance 0.264414)
				)
				(layer "In5.Cu"
					(shape circle)
					(size 0.664718 0.664718)
					(clearance 0.264414)
				)
				(layer "In6.Cu"
					(shape circle)
					(size 0.762 0.762)
					(clearance 0.1651)
				)
				(layer "In7.Cu"
					(shape circle)
					(size 0.762 0.762)
					(clearance 0.1651)
				)
				(layer "In8.Cu"
					(shape circle)
					(size 0.762 0.762)
					(clearance 0.1651)
				)
				(layer "In9.Cu"
					(shape circle)
					(size 0.762 0.762)
					(clearance 0.1651)
				)
				(layer "In10.Cu"
					(shape circle)
					(size 0.762 0.762)
					(clearance 0.1651)
				)
				(layer "B.Cu"
					(shape circle)
					(size 0.762 0.762)
					(thermal_gap 0.1651)
					(clearance 0.1651)
				)
			)
		)
		(pad "F4" thru_hole circle
			(at 5.40004 -9.59993)
			(size 0.664718 0.664718)
			(drill 0.359918)
			(layers "*.Cu" "*.Mask")
			(remove_unused_layers no)
			(net "PCIE_IOM_A_TO_COMP_A_11_DP")
			(clearance 0.264414)
			(padstack
				(mode custom)
				(layer "In1.Cu"
					(shape circle)
					(size 0.664718 0.664718)
					(clearance 0.264414)
				)
				(layer "In2.Cu"
					(shape circle)
					(size 0.664718 0.664718)
					(clearance 0.264414)
				)
				(layer "In3.Cu"
					(shape circle)
					(size 0.664718 0.664718)
					(clearance 0.264414)
				)
				(layer "In4.Cu"
					(shape circle)
					(size 0.664718 0.664718)
					(clearance 0.264414)
				)
				(layer "In5.Cu"
					(shape circle)
					(size 0.664718 0.664718)
					(clearance 0.264414)
				)
				(layer "In6.Cu"
					(shape circle)
					(size 0.762 0.762)
					(clearance 0.1651)
				)
				(layer "In7.Cu"
					(shape circle)
					(size 0.762 0.762)
					(clearance 0.1651)
				)
				(layer "In8.Cu"
					(shape circle)
					(size 0.762 0.762)
					(clearance 0.1651)
				)
				(layer "In9.Cu"
					(shape circle)
					(size 0.762 0.762)
					(clearance 0.1651)
				)
				(layer "In10.Cu"
					(shape circle)
					(size 0.762 0.762)
					(clearance 0.1651)
				)
				(layer "B.Cu"
					(shape circle)
					(size 0.762 0.762)
					(thermal_gap 0.1651)
					(clearance 0.1651)
				)
			)
		)
		(pad "F5" thru_hole circle
			(at 7.199884 -8.599932)
			(size 0.664718 0.664718)
			(drill 0.359918)
			(layers "*.Cu" "*.Mask")
			(remove_unused_layers no)
			(net "PCIE_IOM_A_TO_COMP_A_12_DP")
			(clearance 0.264414)
			(padstack
				(mode custom)
				(layer "In1.Cu"
					(shape circle)
					(size 0.664718 0.664718)
					(clearance 0.264414)
				)
				(layer "In2.Cu"
					(shape circle)
					(size 0.664718 0.664718)
					(clearance 0.264414)
				)
				(layer "In3.Cu"
					(shape circle)
					(size 0.664718 0.664718)
					(clearance 0.264414)
				)
				(layer "In4.Cu"
					(shape circle)
					(size 0.664718 0.664718)
					(clearance 0.264414)
				)
				(layer "In5.Cu"
					(shape circle)
					(size 0.664718 0.664718)
					(clearance 0.264414)
				)
				(layer "In6.Cu"
					(shape circle)
					(size 0.762 0.762)
					(clearance 0.1651)
				)
				(layer "In7.Cu"
					(shape circle)
					(size 0.762 0.762)
					(clearance 0.1651)
				)
				(layer "In8.Cu"
					(shape circle)
					(size 0.762 0.762)
					(clearance 0.1651)
				)
				(layer "In9.Cu"
					(shape circle)
					(size 0.762 0.762)
					(clearance 0.1651)
				)
				(layer "In10.Cu"
					(shape circle)
					(size 0.762 0.762)
					(clearance 0.1651)
				)
				(layer "B.Cu"
					(shape circle)
					(size 0.762 0.762)
					(thermal_gap 0.1651)
					(clearance 0.1651)
				)
			)
		)
		(pad "F6" thru_hole circle
			(at 8.999982 -9.59993)
			(size 0.664718 0.664718)
			(drill 0.359918)
			(layers "*.Cu" "*.Mask")
			(remove_unused_layers no)
			(net "PCIE_IOM_A_TO_COMP_A_13_DP")
			(clearance 0.264414)
			(padstack
				(mode custom)
				(layer "In1.Cu"
					(shape circle)
					(size 0.664718 0.664718)
					(clearance 0.264414)
				)
				(layer "In2.Cu"
					(shape circle)
					(size 0.664718 0.664718)
					(clearance 0.264414)
				)
				(layer "In3.Cu"
					(shape circle)
					(size 0.664718 0.664718)
					(clearance 0.264414)
				)
				(layer "In4.Cu"
					(shape circle)
					(size 0.664718 0.664718)
					(clearance 0.264414)
				)
				(layer "In5.Cu"
					(shape circle)
					(size 0.664718 0.664718)
					(clearance 0.264414)
				)
				(layer "In6.Cu"
					(shape circle)
					(size 0.762 0.762)
					(clearance 0.1651)
				)
				(layer "In7.Cu"
					(shape circle)
					(size 0.762 0.762)
					(clearance 0.1651)
				)
				(layer "In8.Cu"
					(shape circle)
					(size 0.762 0.762)
					(clearance 0.1651)
				)
				(layer "In9.Cu"
					(shape circle)
					(size 0.762 0.762)
					(clearance 0.1651)
				)
				(layer "In10.Cu"
					(shape circle)
					(size 0.762 0.762)
					(clearance 0.1651)
				)
				(layer "B.Cu"
					(shape circle)
					(size 0.762 0.762)
					(thermal_gap 0.1651)
					(clearance 0.1651)
				)
			)
		)
		(pad "F7" thru_hole circle
			(at 10.80008 -8.599932)
			(size 0.664718 0.664718)
			(drill 0.359918)
			(layers "*.Cu" "*.Mask")
			(remove_unused_layers no)
			(net "PCIE_IOM_A_TO_COMP_A_14_DP")
			(clearance 0.264414)
			(padstack
				(mode custom)
				(layer "In1.Cu"
					(shape circle)
					(size 0.664718 0.664718)
					(clearance 0.264414)
				)
				(layer "In2.Cu"
					(shape circle)
					(size 0.664718 0.664718)
					(clearance 0.264414)
				)
				(layer "In3.Cu"
					(shape circle)
					(size 0.664718 0.664718)
					(clearance 0.264414)
				)
				(layer "In4.Cu"
					(shape circle)
					(size 0.664718 0.664718)
					(clearance 0.264414)
				)
				(layer "In5.Cu"
					(shape circle)
					(size 0.664718 0.664718)
					(clearance 0.264414)
				)
				(layer "In6.Cu"
					(shape circle)
					(size 0.762 0.762)
					(clearance 0.1651)
				)
				(layer "In7.Cu"
					(shape circle)
					(size 0.762 0.762)
					(clearance 0.1651)
				)
				(layer "In8.Cu"
					(shape circle)
					(size 0.762 0.762)
					(clearance 0.1651)
				)
				(layer "In9.Cu"
					(shape circle)
					(size 0.762 0.762)
					(clearance 0.1651)
				)
				(layer "In10.Cu"
					(shape circle)
					(size 0.762 0.762)
					(clearance 0.1651)
				)
				(layer "B.Cu"
					(shape circle)
					(size 0.762 0.762)
					(thermal_gap 0.1651)
					(clearance 0.1651)
				)
			)
		)
		(pad "F8" thru_hole circle
			(at 12.599924 -9.59993)
			(size 0.664718 0.664718)
			(drill 0.359918)
			(layers "*.Cu" "*.Mask")
			(remove_unused_layers no)
			(net "PCIE_IOM_A_TO_COMP_A_15_DP")
			(clearance 0.264414)
			(padstack
				(mode custom)
				(layer "In1.Cu"
					(shape circle)
					(size 0.664718 0.664718)
					(clearance 0.264414)
				)
				(layer "In2.Cu"
					(shape circle)
					(size 0.664718 0.664718)
					(clearance 0.264414)
				)
				(layer "In3.Cu"
					(shape circle)
					(size 0.664718 0.664718)
					(clearance 0.264414)
				)
				(layer "In4.Cu"
					(shape circle)
					(size 0.664718 0.664718)
					(clearance 0.264414)
				)
				(layer "In5.Cu"
					(shape circle)
					(size 0.664718 0.664718)
					(clearance 0.264414)
				)
				(layer "In6.Cu"
					(shape circle)
					(size 0.762 0.762)
					(clearance 0.1651)
				)
				(layer "In7.Cu"
					(shape circle)
					(size 0.762 0.762)
					(clearance 0.1651)
				)
				(layer "In8.Cu"
					(shape circle)
					(size 0.762 0.762)
					(clearance 0.1651)
				)
				(layer "In9.Cu"
					(shape circle)
					(size 0.762 0.762)
					(clearance 0.1651)
				)
				(layer "In10.Cu"
					(shape circle)
					(size 0.762 0.762)
					(clearance 0.1651)
				)
				(layer "B.Cu"
					(shape circle)
					(size 0.762 0.762)
					(thermal_gap 0.1651)
					(clearance 0.1651)
				)
			)
		)
		(pad "F9" thru_hole circle
			(at 21.599906 -8.599932)
			(size 0.664718 0.664718)
			(drill 0.359918)
			(layers "*.Cu" "*.Mask")
			(remove_unused_layers no)
			(net "PCIE_IOM_A_TO_COMP_A_16_DP")
			(clearance 0.264414)
			(padstack
				(mode custom)
				(layer "In1.Cu"
					(shape circle)
					(size 0.664718 0.664718)
					(clearance 0.264414)
				)
				(layer "In2.Cu"
					(shape circle)
					(size 0.664718 0.664718)
					(clearance 0.264414)
				)
				(layer "In3.Cu"
					(shape circle)
					(size 0.664718 0.664718)
					(clearance 0.264414)
				)
				(layer "In4.Cu"
					(shape circle)
					(size 0.664718 0.664718)
					(clearance 0.264414)
				)
				(layer "In5.Cu"
					(shape circle)
					(size 0.664718 0.664718)
					(clearance 0.264414)
				)
				(layer "In6.Cu"
					(shape circle)
					(size 0.762 0.762)
					(clearance 0.1651)
				)
				(layer "In7.Cu"
					(shape circle)
					(size 0.762 0.762)
					(clearance 0.1651)
				)
				(layer "In8.Cu"
					(shape circle)
					(size 0.762 0.762)
					(clearance 0.1651)
				)
				(layer "In9.Cu"
					(shape circle)
					(size 0.762 0.762)
					(clearance 0.1651)
				)
				(layer "In10.Cu"
					(shape circle)
					(size 0.762 0.762)
					(clearance 0.1651)
				)
				(layer "B.Cu"
					(shape circle)
					(size 0.762 0.762)
					(thermal_gap 0.1651)
					(clearance 0.1651)
				)
			)
		)
		(pad "F10" thru_hole circle
			(at 23.400004 -9.59993)
			(size 0.664718 0.664718)
			(drill 0.359918)
			(layers "*.Cu" "*.Mask")
			(remove_unused_layers no)
			(net "PCIE_IOM_A_TO_COMP_A_17_DP")
			(clearance 0.264414)
			(padstack
				(mode custom)
				(layer "In1.Cu"
					(shape circle)
					(size 0.664718 0.664718)
					(clearance 0.264414)
				)
				(layer "In2.Cu"
					(shape circle)
					(size 0.664718 0.664718)
					(clearance 0.264414)
				)
				(layer "In3.Cu"
					(shape circle)
					(size 0.664718 0.664718)
					(clearance 0.264414)
				)
				(layer "In4.Cu"
					(shape circle)
					(size 0.664718 0.664718)
					(clearance 0.264414)
				)
				(layer "In5.Cu"
					(shape circle)
					(size 0.664718 0.664718)
					(clearance 0.264414)
				)
				(layer "In6.Cu"
					(shape circle)
					(size 0.762 0.762)
					(clearance 0.1651)
				)
				(layer "In7.Cu"
					(shape circle)
					(size 0.762 0.762)
					(clearance 0.1651)
				)
				(layer "In8.Cu"
					(shape circle)
					(size 0.762 0.762)
					(clearance 0.1651)
				)
				(layer "In9.Cu"
					(shape circle)
					(size 0.762 0.762)
					(clearance 0.1651)
				)
				(layer "In10.Cu"
					(shape circle)
					(size 0.762 0.762)
					(clearance 0.1651)
				)
				(layer "B.Cu"
					(shape circle)
					(size 0.762 0.762)
					(thermal_gap 0.1651)
					(clearance 0.1651)
				)
			)
		)
		(pad "F11" thru_hole circle
			(at 25.200102 -8.599932)
			(size 0.664718 0.664718)
			(drill 0.359918)
			(layers "*.Cu" "*.Mask")
			(remove_unused_layers no)
			(net "PCIE_IOM_A_TO_COMP_A_18_DP")
			(clearance 0.264414)
			(padstack
				(mode custom)
				(layer "In1.Cu"
					(shape circle)
					(size 0.664718 0.664718)
					(clearance 0.264414)
				)
				(layer "In2.Cu"
					(shape circle)
					(size 0.664718 0.664718)
					(clearance 0.264414)
				)
				(layer "In3.Cu"
					(shape circle)
					(size 0.664718 0.664718)
					(clearance 0.264414)
				)
				(layer "In4.Cu"
					(shape circle)
					(size 0.664718 0.664718)
					(clearance 0.264414)
				)
				(layer "In5.Cu"
					(shape circle)
					(size 0.664718 0.664718)
					(clearance 0.264414)
				)
				(layer "In6.Cu"
					(shape circle)
					(size 0.762 0.762)
					(clearance 0.1651)
				)
				(layer "In7.Cu"
					(shape circle)
					(size 0.762 0.762)
					(clearance 0.1651)
				)
				(layer "In8.Cu"
					(shape circle)
					(size 0.762 0.762)
					(clearance 0.1651)
				)
				(layer "In9.Cu"
					(shape circle)
					(size 0.762 0.762)
					(clearance 0.1651)
				)
				(layer "In10.Cu"
					(shape circle)
					(size 0.762 0.762)
					(clearance 0.1651)
				)
				(layer "B.Cu"
					(shape circle)
					(size 0.762 0.762)
					(thermal_gap 0.1651)
					(clearance 0.1651)
				)
			)
		)
		(pad "F12" thru_hole circle
			(at 26.999946 -9.59993)
			(size 0.664718 0.664718)
			(drill 0.359918)
			(layers "*.Cu" "*.Mask")
			(remove_unused_layers no)
			(net "PCIE_IOM_A_TO_COMP_A_19_DP")
			(clearance 0.264414)
			(padstack
				(mode custom)
				(layer "In1.Cu"
					(shape circle)
					(size 0.664718 0.664718)
					(clearance 0.264414)
				)
				(layer "In2.Cu"
					(shape circle)
					(size 0.664718 0.664718)
					(clearance 0.264414)
				)
				(layer "In3.Cu"
					(shape circle)
					(size 0.664718 0.664718)
					(clearance 0.264414)
				)
				(layer "In4.Cu"
					(shape circle)
					(size 0.664718 0.664718)
					(clearance 0.264414)
				)
				(layer "In5.Cu"
					(shape circle)
					(size 0.664718 0.664718)
					(clearance 0.264414)
				)
				(layer "In6.Cu"
					(shape circle)
					(size 0.762 0.762)
					(clearance 0.1651)
				)
				(layer "In7.Cu"
					(shape circle)
					(size 0.762 0.762)
					(clearance 0.1651)
				)
				(layer "In8.Cu"
					(shape circle)
					(size 0.762 0.762)
					(clearance 0.1651)
				)
				(layer "In9.Cu"
					(shape circle)
					(size 0.762 0.762)
					(clearance 0.1651)
				)
				(layer "In10.Cu"
					(shape circle)
					(size 0.762 0.762)
					(clearance 0.1651)
				)
				(layer "B.Cu"
					(shape circle)
					(size 0.762 0.762)
					(thermal_gap 0.1651)
					(clearance 0.1651)
				)
			)
		)
		(pad "F13" thru_hole circle
			(at 28.800044 -8.599932)
			(size 0.664718 0.664718)
			(drill 0.359918)
			(layers "*.Cu" "*.Mask")
			(remove_unused_layers no)
			(net "PCIE_IOM_A_TO_COMP_A_20_DP")
			(clearance 0.264414)
			(padstack
				(mode custom)
				(layer "In1.Cu"
					(shape circle)
					(size 0.664718 0.664718)
					(clearance 0.264414)
				)
				(layer "In2.Cu"
					(shape circle)
					(size 0.664718 0.664718)
					(clearance 0.264414)
				)
				(layer "In3.Cu"
					(shape circle)
					(size 0.664718 0.664718)
					(clearance 0.264414)
				)
				(layer "In4.Cu"
					(shape circle)
					(size 0.664718 0.664718)
					(clearance 0.264414)
				)
				(layer "In5.Cu"
					(shape circle)
					(size 0.664718 0.664718)
					(clearance 0.264414)
				)
				(layer "In6.Cu"
					(shape circle)
					(size 0.762 0.762)
					(clearance 0.1651)
				)
				(layer "In7.Cu"
					(shape circle)
					(size 0.762 0.762)
					(clearance 0.1651)
				)
				(layer "In8.Cu"
					(shape circle)
					(size 0.762 0.762)
					(clearance 0.1651)
				)
				(layer "In9.Cu"
					(shape circle)
					(size 0.762 0.762)
					(clearance 0.1651)
				)
				(layer "In10.Cu"
					(shape circle)
					(size 0.762 0.762)
					(clearance 0.1651)
				)
				(layer "B.Cu"
					(shape circle)
					(size 0.762 0.762)
					(thermal_gap 0.1651)
					(clearance 0.1651)
				)
			)
		)
	)
)
